(kicad_pcb
	(version 20241229)
	(generator "pcbnew")
	(generator_version "9.0")
	(general
		(thickness 1.294)
		(legacy_teardrops no)
	)
	(paper "A3")
	(title_block
		(title "Kintex 410T devboard")
		(date "2024-04-03")
		(rev "1.1.2")
		(comment 9 "footprints 615-620 of 975")
	)
	(layers
		(0 "F.Cu" mixed)
		(4 "In1.Cu" power)
		(6 "In2.Cu" power)
		(8 "In3.Cu" mixed)
		(10 "In4.Cu" power)
		(12 "In5.Cu" mixed)
		(14 "In6.Cu" power)
		(16 "In7.Cu" mixed)
		(18 "In8.Cu" power)
		(2 "B.Cu" mixed)
		(9 "F.Adhes" user "F.Adhesive")
		(11 "B.Adhes" user "B.Adhesive")
		(13 "F.Paste" user)
		(15 "B.Paste" user)
		(5 "F.SilkS" user "F.Silkscreen")
		(7 "B.SilkS" user "B.Silkscreen")
		(1 "F.Mask" user)
		(3 "B.Mask" user)
		(17 "Dwgs.User" user "User.Drawings")
		(19 "Cmts.User" user "User.Comments")
		(21 "Eco1.User" user "User.Eco1")
		(23 "Eco2.User" user "User.Eco2")
		(25 "Edge.Cuts" user)
		(27 "Margin" user)
		(31 "F.CrtYd" user "F.Courtyard")
		(29 "B.CrtYd" user "B.Courtyard")
		(35 "F.Fab" user)
		(33 "B.Fab" user)
	)
	(footprint "antmicro-footprints:FB_0603_1608Metric"
		(layer "B.Cu")
		(at 249.401 112.6)
		(property "Reference" "FB9"
			(at -1.251 0.35 180)
			(layer "B.SilkS")
			(effects
				(font
					(size 0.7 0.7)
					(thickness 0.15)
				)
				(justify left bottom mirror)
			)
		)
		(property "Value" "FB_120Z_2A_Murata-BLM18PG_0603"
			(at 0 -1.7 180)
			(layer "B.Fab")
			(effects
				(font
					(size 0.7 0.7)
					(thickness 0.15)
				)
				(justify left bottom mirror)
			)
		)
		(property "Description" "Ferrite Bead, 0603 [1608 Metric], 120 ohm, 2 A, BLM18P, 0.05 ohm, ± 25%, DC power line"
			(at 0 0 0)
			(layer "F.Fab")
			(hide yes)
			(effects
				(font
					(size 1.27 1.27)
					(thickness 0.15)
				)
			)
		)
		(property "Author" "Antmicro"
			(at 0 0 0)
			(layer "B.Fab")
			(hide yes)
			(effects
				(font
					(size 1 1)
					(thickness 0.15)
				)
				(justify mirror)
			)
		)
		(property "Current" ""
			(at 0 0 0)
			(layer "B.Fab")
			(hide yes)
			(effects
				(font
					(size 1 1)
					(thickness 0.15)
				)
				(justify mirror)
			)
		)
		(property "License" "Apache-2.0"
			(at 0 0 0)
			(layer "B.Fab")
			(hide yes)
			(effects
				(font
					(size 1 1)
					(thickness 0.15)
				)
				(justify mirror)
			)
		)
		(property "MPN" "BLM18PG121SN1D"
			(at 0 0 0)
			(layer "B.Fab")
			(hide yes)
			(effects
				(font
					(size 1 1)
					(thickness 0.15)
				)
				(justify mirror)
			)
		)
		(property "Manufacturer" "Murata"
			(at 0 0 0)
			(layer "B.Fab")
			(hide yes)
			(effects
				(font
					(size 1 1)
					(thickness 0.15)
				)
				(justify mirror)
			)
		)
		(property "Val" "120Z/2A"
			(at 0 0 0)
			(layer "B.Fab")
			(hide yes)
			(effects
				(font
					(size 1 1)
					(thickness 0.15)
				)
				(justify mirror)
			)
		)
		(sheetname "HDMI + Ethernet")
		(sheetfile "hdmi-ethernet.kicad_sch")
		(attr smd)
		(fp_line
			(start -0.15 -0.4)
			(end 0.15 -0.4)
			(stroke
				(width 0.15)
				(type solid)
			)
			(layer "B.SilkS")
		)
		(fp_line
			(start -0.15 0.4)
			(end 0.15 0.4)
			(stroke
				(width 0.15)
				(type solid)
			)
			(layer "B.SilkS")
		)
		(fp_rect
			(start -1.25 0.65)
			(end 1.25 -0.65)
			(stroke
				(width 0.05)
				(type solid)
			)
			(fill no)
			(layer "B.CrtYd")
		)
		(fp_line
			(start -0.803 -0.406)
			(end -0.803 0.408)
			(stroke
				(width 0.15)
				(type solid)
			)
			(layer "B.Fab")
		)
		(fp_line
			(start 0.8 -0.406)
			(end -0.803 -0.406)
			(stroke
				(width 0.15)
				(type solid)
			)
			(layer "B.Fab")
		)
		(fp_line
			(start 0.8 0.408)
			(end -0.803 0.408)
			(stroke
				(width 0.15)
				(type solid)
			)
			(layer "B.Fab")
		)
		(fp_line
			(start 0.8 0.408)
			(end 0.8 -0.406)
			(stroke
				(width 0.15)
				(type solid)
			)
			(layer "B.Fab")
		)
		(pad "1" smd roundrect
			(at -0.7 0)
			(size 0.8 1)
			(layers "B.Cu" "B.Mask" "B.Paste")
			(roundrect_rratio 0.2)
			(net 703 "+5V")
			(pintype "passive")
		)
		(pad "2" smd roundrect
			(at 0.7 0)
			(size 0.8 1)
			(layers "B.Cu" "B.Mask" "B.Paste")
			(roundrect_rratio 0.2)
			(net 795 "/HDMI + Ethernet/HDMI_5V")
			(pintype "passive")
		)
	)
	(footprint "antmicro-footprints:C_0201"
		(layer "B.Cu")
		(at 201.5 132.85)
		(descr "Capacitor SMD 0201")
		(tags "capacitor SMD 0201")
		(property "Reference" "C139"
			(at 24.4 -28.4 0)
			(layer "B.SilkS")
			(effects
				(font
					(size 0.7 0.7)
					(thickness 0.15)
				)
				(justify right bottom mirror)
			)
		)
		(property "Value" "C_100n_0201"
			(at 0 -1.4 0)
			(layer "B.Fab")
			(effects
				(font
					(size 0.7 0.7)
					(thickness 0.15)
				)
				(justify right bottom mirror)
			)
		)
		(property "Description" "SMD Multilayer Ceramic Capacitor, 0.1 µF, 6.3 V, 0201 [0603 Metric], ± 10%, X6S, CC Series"
			(at 0 0 0)
			(layer "F.Fab")
			(hide yes)
			(effects
				(font
					(size 1.27 1.27)
					(thickness 0.15)
				)
			)
		)
		(property "Author" "Antmicro"
			(at 0 0 0)
			(layer "B.Fab")
			(hide yes)
			(effects
				(font
					(size 1 1)
					(thickness 0.15)
				)
				(justify mirror)
			)
		)
		(property "Dielectric" ""
			(at 0 0 0)
			(layer "B.Fab")
			(hide yes)
			(effects
				(font
					(size 1 1)
					(thickness 0.15)
				)
				(justify mirror)
			)
		)
		(property "License" "Apache-2.0"
			(at 0 0 0)
			(layer "B.Fab")
			(hide yes)
			(effects
				(font
					(size 1 1)
					(thickness 0.15)
				)
				(justify mirror)
			)
		)
		(property "MPN" "CC0201KRX6S5BB104"
			(at 0 0 0)
			(layer "B.Fab")
			(hide yes)
			(effects
				(font
					(size 1 1)
					(thickness 0.15)
				)
				(justify mirror)
			)
		)
		(property "Manufacturer" "YAGEO"
			(at 0 0 0)
			(layer "B.Fab")
			(hide yes)
			(effects
				(font
					(size 1 1)
					(thickness 0.15)
				)
				(justify mirror)
			)
		)
		(property "Val" "100n"
			(at 0 0 0)
			(layer "B.Fab")
			(hide yes)
			(effects
				(font
					(size 1 1)
					(thickness 0.15)
				)
				(justify mirror)
			)
		)
		(property "Voltage" ""
			(at 0 0 0)
			(layer "B.Fab")
			(hide yes)
			(effects
				(font
					(size 1 1)
					(thickness 0.15)
				)
				(justify mirror)
			)
		)
		(sheetname "FPGA supply")
		(sheetfile "fpga-supply.kicad_sch")
		(attr smd)
		(fp_rect
			(start -0.7 0.35)
			(end 0.7 -0.35)
			(stroke
				(width 0.05)
				(type default)
			)
			(fill no)
			(layer "B.CrtYd")
		)
		(fp_rect
			(start 0.3 -0.15)
			(end -0.301 0.149)
			(stroke
				(width 0.15)
				(type solid)
			)
			(fill no)
			(layer "B.Fab")
		)
		(pad "" smd roundrect
			(at -0.349 0.002)
			(size 0.318 0.36)
			(layers "B.Paste")
			(roundrect_rratio 0.25)
		)
		(pad "" smd roundrect
			(at 0.341 0.002)
			(size 0.318 0.36)
			(layers "B.Paste")
			(roundrect_rratio 0.25)
		)
		(pad "1" smd roundrect
			(at -0.321 0.002)
			(size 0.46 0.4)
			(layers "B.Cu" "B.Mask")
			(roundrect_rratio 0.25)
			(net 1 "GND")
			(pintype "passive")
		)
		(pad "2" smd roundrect
			(at 0.32 0.002)
			(size 0.46 0.4)
			(layers "B.Cu" "B.Mask")
			(roundrect_rratio 0.25)
			(net 650 "+1V0")
			(pintype "passive")
		)
	)
	(footprint "antmicro-footprints:C_0402_1005Metric"
		(layer "B.Cu")
		(at 168.049999 148.924999 90)
		(descr "Capacitor SMD 0402")
		(tags "capacitor SMD 0402")
		(property "Reference" "C184"
			(at -0.775001 0.400001 270)
			(layer "B.SilkS")
			(effects
				(font
					(size 0.7 0.7)
					(thickness 0.15)
				)
				(justify left bottom mirror)
			)
		)
		(property "Value" "C_100n_0402"
			(at 0 -1.169 270)
			(layer "B.Fab")
			(effects
				(font
					(size 0.7 0.7)
					(thickness 0.15)
				)
				(justify left bottom mirror)
			)
		)
		(property "Description" "SMD Multilayer Ceramic Capacitor, 0.1 µF, 50 V, 0402 [1005 Metric], ± 10%, X5R, GRM Series"
			(at 0 0 90)
			(layer "F.Fab")
			(hide yes)
			(effects
				(font
					(size 1.27 1.27)
					(thickness 0.15)
				)
			)
		)
		(property "Author" "Antmicro"
			(at 316.974998 -19.125 0)
			(layer "B.Fab")
			(hide yes)
			(effects
				(font
					(size 1 1)
					(thickness 0.15)
				)
				(justify mirror)
			)
		)
		(property "Dielectric" "X5R"
			(at 316.974998 -19.125 0)
			(layer "B.Fab")
			(hide yes)
			(effects
				(font
					(size 1 1)
					(thickness 0.15)
				)
				(justify mirror)
			)
		)
		(property "License" "Apache-2.0"
			(at 316.974998 -19.125 0)
			(layer "B.Fab")
			(hide yes)
			(effects
				(font
					(size 1 1)
					(thickness 0.15)
				)
				(justify mirror)
			)
		)
		(property "MPN" "GRM155R61H104KE14D"
			(at 316.974998 -19.125 0)
			(layer "B.Fab")
			(hide yes)
			(effects
				(font
					(size 1 1)
					(thickness 0.15)
				)
				(justify mirror)
			)
		)
		(property "Manufacturer" "Murata"
			(at 316.974998 -19.125 0)
			(layer "B.Fab")
			(hide yes)
			(effects
				(font
					(size 1 1)
					(thickness 0.15)
				)
				(justify mirror)
			)
		)
		(property "Val" "100n"
			(at 316.974998 -19.125 0)
			(layer "B.Fab")
			(hide yes)
			(effects
				(font
					(size 1 1)
					(thickness 0.15)
				)
				(justify mirror)
			)
		)
		(property "Voltage" "50V"
			(at 316.974998 -19.125 0)
			(layer "B.Fab")
			(hide yes)
			(effects
				(font
					(size 1 1)
					(thickness 0.15)
				)
				(justify mirror)
			)
		)
		(sheetname "DRAM + SRAM")
		(sheetfile "ram.kicad_sch")
		(attr smd)
		(fp_rect
			(start -0.925 0.47)
			(end 0.925 -0.47)
			(stroke
				(width 0.05)
				(type default)
			)
			(fill no)
			(layer "B.CrtYd")
		)
		(fp_line
			(start 0.504 -0.248)
			(end -0.494 -0.248)
			(stroke
				(width 0.15)
				(type solid)
			)
			(layer "B.Fab")
		)
		(fp_line
			(start -0.494 -0.248)
			(end -0.494 0.25)
			(stroke
				(width 0.15)
				(type solid)
			)
			(layer "B.Fab")
		)
		(fp_line
			(start 0.504 0.25)
			(end 0.504 -0.248)
			(stroke
				(width 0.15)
				(type solid)
			)
			(layer "B.Fab")
		)
		(fp_line
			(start -0.494 0.25)
			(end 0.504 0.25)
			(stroke
				(width 0.15)
				(type solid)
			)
			(layer "B.Fab")
		)
		(pad "1" smd roundrect
			(at -0.48 0 90)
			(size 0.59 0.64)
			(layers "B.Cu" "B.Mask" "B.Paste")
			(roundrect_rratio 0.25)
			(net 1 "GND")
			(pintype "passive")
		)
		(pad "2" smd roundrect
			(at 0.48 0 90)
			(size 0.59 0.64)
			(layers "B.Cu" "B.Mask" "B.Paste")
			(roundrect_rratio 0.25)
			(net 11 "+0V675_VREF")
			(pintype "passive")
		)
	)
	(footprint "antmicro-footprints:R_0402_1005Metric"
		(layer "B.Cu")
		(at 156.4625 173.7 -90)
		(descr "Resistor SMD 0402")
		(tags "resistor SMD 0402")
		(property "Reference" "R312"
			(at 0.75 -0.3875 90)
			(layer "B.SilkS")
			(effects
				(font
					(size 0.7 0.7)
					(thickness 0.15)
				)
				(justify left bottom mirror)
			)
		)
		(property "Value" "R_0R_0402"
			(at 0 -1.4 90)
			(layer "B.Fab")
			(effects
				(font
					(size 0.7 0.7)
					(thickness 0.15)
				)
				(justify left bottom mirror)
			)
		)
		(property "Description" "SMD Chip Resistor, Jumper, 0 ohm, 100 mW, 0402 [1005 Metric], Thick Film, General Purpose"
			(at 0 0 270)
			(layer "F.Fab")
			(hide yes)
			(effects
				(font
					(size 1.27 1.27)
					(thickness 0.15)
				)
			)
		)
		(property "Author" "Antmicro"
			(at -17.2375 330.1625 0)
			(layer "B.Fab")
			(hide yes)
			(effects
				(font
					(size 1 1)
					(thickness 0.15)
				)
				(justify mirror)
			)
		)
		(property "Current" "1A"
			(at -17.2375 330.1625 0)
			(layer "B.Fab")
			(hide yes)
			(effects
				(font
					(size 1 1)
					(thickness 0.15)
				)
				(justify mirror)
			)
		)
		(property "DNP" "DNP"
			(at -17.2375 330.1625 0)
			(layer "B.Fab")
			(hide yes)
			(effects
				(font
					(size 1 1)
					(thickness 0.15)
				)
				(justify mirror)
			)
		)
		(property "License" "Apache-2.0"
			(at -17.2375 330.1625 0)
			(layer "B.Fab")
			(hide yes)
			(effects
				(font
					(size 1 1)
					(thickness 0.15)
				)
				(justify mirror)
			)
		)
		(property "MPN" "ERJ2GE0R00X"
			(at -17.2375 330.1625 0)
			(layer "B.Fab")
			(hide yes)
			(effects
				(font
					(size 1 1)
					(thickness 0.15)
				)
				(justify mirror)
			)
		)
		(property "Manufacturer" "Panasonic"
			(at -17.2375 330.1625 0)
			(layer "B.Fab")
			(hide yes)
			(effects
				(font
					(size 1 1)
					(thickness 0.15)
				)
				(justify mirror)
			)
		)
		(property "Tolerance" ""
			(at -17.2375 330.1625 0)
			(layer "B.Fab")
			(hide yes)
			(effects
				(font
					(size 1 1)
					(thickness 0.15)
				)
				(justify mirror)
			)
		)
		(property "Val" "0R"
			(at -17.2375 330.1625 0)
			(layer "B.Fab")
			(hide yes)
			(effects
				(font
					(size 1 1)
					(thickness 0.15)
				)
				(justify mirror)
			)
		)
		(property "dnp" ""
			(at -17.2375 330.1625 0)
			(layer "B.Fab")
			(hide yes)
			(effects
				(font
					(size 1 1)
					(thickness 0.15)
				)
				(justify mirror)
			)
		)
		(property "exclude_from_bom" ""
			(at -17.2375 330.1625 0)
			(layer "B.Fab")
			(hide yes)
			(effects
				(font
					(size 1 1)
					(thickness 0.15)
				)
				(justify mirror)
			)
		)
		(sheetname "DC-DC Converters")
		(sheetfile "dc-dc.kicad_sch")
		(attr smd exclude_from_bom)
		(fp_rect
			(start -0.925 0.47)
			(end 0.925 -0.47)
			(stroke
				(width 0.05)
				(type default)
			)
			(fill no)
			(layer "B.CrtYd")
		)
		(fp_rect
			(start -0.5 0.25)
			(end 0.5 -0.25)
			(stroke
				(width 0.15)
				(type solid)
			)
			(fill no)
			(layer "B.Fab")
		)
		(pad "1" smd roundrect
			(at -0.48 0 270)
			(size 0.59 0.64)
			(layers "B.Cu" "B.Mask" "B.Paste")
			(roundrect_rratio 0.25)
			(net 1 "GND")
			(pintype "passive")
		)
		(pad "2" smd roundrect
			(at 0.48 0 270)
			(size 0.59 0.64)
			(layers "B.Cu" "B.Mask" "B.Paste")
			(roundrect_rratio 0.25)
			(net 963 "/DC-DC Converters/FB4")
			(pintype "passive")
		)
	)
	(footprint "antmicro-footprints:C_0603_1608Metric"
		(layer "B.Cu")
		(at 210.25 130 180)
		(descr "Capacitor SMD 0603")
		(tags "capacitor 0603")
		(property "Reference" "C5"
			(at -1.175 -1.375 0)
			(layer "B.SilkS")
			(effects
				(font
					(size 0.7 0.7)
					(thickness 0.15)
				)
				(justify left bottom mirror)
			)
		)
		(property "Value" "C_47u_0603"
			(at 0 -1.6 0)
			(layer "B.Fab")
			(effects
				(font
					(size 0.7 0.7)
					(thickness 0.15)
				)
				(justify left bottom mirror)
			)
		)
		(property "Description" "SMD Multilayer Ceramic Capacitor, 47 µF, 6.3 V, 0603 [1608 Metric], ± 20%, X5R, GRM Series"
			(at 0 0 180)
			(layer "F.Fab")
			(hide yes)
			(effects
				(font
					(size 1.27 1.27)
					(thickness 0.15)
				)
			)
		)
		(property "Author" "Antmicro"
			(at 420.5 260 0)
			(layer "B.Fab")
			(hide yes)
			(effects
				(font
					(size 1 1)
					(thickness 0.15)
				)
				(justify mirror)
			)
		)
		(property "Dielectric" ""
			(at 420.5 260 0)
			(layer "B.Fab")
			(hide yes)
			(effects
				(font
					(size 1 1)
					(thickness 0.15)
				)
				(justify mirror)
			)
		)
		(property "License" "Apache-2.0"
			(at 420.5 260 0)
			(layer "B.Fab")
			(hide yes)
			(effects
				(font
					(size 1 1)
					(thickness 0.15)
				)
				(justify mirror)
			)
		)
		(property "MPN" "GRM188R60J476ME15D"
			(at 420.5 260 0)
			(layer "B.Fab")
			(hide yes)
			(effects
				(font
					(size 1 1)
					(thickness 0.15)
				)
				(justify mirror)
			)
		)
		(property "Manufacturer" "Murata"
			(at 420.5 260 0)
			(layer "B.Fab")
			(hide yes)
			(effects
				(font
					(size 1 1)
					(thickness 0.15)
				)
				(justify mirror)
			)
		)
		(property "Val" "47u"
			(at 420.5 260 0)
			(layer "B.Fab")
			(hide yes)
			(effects
				(font
					(size 1 1)
					(thickness 0.15)
				)
				(justify mirror)
			)
		)
		(property "Voltage" ""
			(at 420.5 260 0)
			(layer "B.Fab")
			(hide yes)
			(effects
				(font
					(size 1 1)
					(thickness 0.15)
				)
				(justify mirror)
			)
		)
		(sheetname "FPGA Bank 14 & 15")
		(sheetfile "fpga-bank-14-15.kicad_sch")
		(attr smd)
		(fp_line
			(start -0.15 0.4)
			(end 0.15 0.4)
			(stroke
				(width 0.15)
				(type solid)
			)
			(layer "B.SilkS")
		)
		(fp_line
			(start -0.15 -0.4)
			(end 0.15 -0.4)
			(stroke
				(width 0.15)
				(type solid)
			)
			(layer "B.SilkS")
		)
		(fp_rect
			(start -1.25 0.65)
			(end 1.25 -0.65)
			(stroke
				(width 0.05)
				(type solid)
			)
			(fill no)
			(layer "B.CrtYd")
		)
		(fp_rect
			(start -0.8 0.4)
			(end 0.8 -0.4)
			(stroke
				(width 0.15)
				(type solid)
			)
			(fill no)
			(layer "B.Fab")
		)
		(pad "1" smd roundrect
			(at -0.7 0 180)
			(size 0.8 1)
			(layers "B.Cu" "B.Mask" "B.Paste")
			(roundrect_rratio 0.2)
			(net 1 "GND")
			(pintype "passive")
		)
		(pad "2" smd roundrect
			(at 0.7 0 180)
			(size 0.8 1)
			(layers "B.Cu" "B.Mask" "B.Paste")
			(roundrect_rratio 0.2)
			(net 24 "+3V3")
			(pintype "passive")
		)
	)
	(footprint "antmicro-footprints:C_0402_1005Metric"
		(layer "B.Cu")
		(at 170.5 143.2 90)
		(descr "Capacitor SMD 0402")
		(tags "capacitor SMD 0402")
		(property "Reference" "C295"
			(at 1.075 2.35 270)
			(layer "B.SilkS")
			(effects
				(font
					(size 0.7 0.7)
					(thickness 0.15)
				)
				(justify left bottom mirror)
			)
		)
		(property "Value" "C_100n_0402"
			(at 0 -1.169 270)
			(layer "B.Fab")
			(effects
				(font
					(size 0.7 0.7)
					(thickness 0.15)
				)
				(justify left bottom mirror)
			)
		)
		(property "Description" "SMD Multilayer Ceramic Capacitor, 0.1 µF, 50 V, 0402 [1005 Metric], ± 10%, X5R, GRM Series"
			(at 0 0 90)
			(layer "F.Fab")
			(hide yes)
			(effects
				(font
					(size 1.27 1.27)
					(thickness 0.15)
				)
			)
		)
		(property "Author" "Antmicro"
			(at 313.7 -27.3 0)
			(layer "B.Fab")
			(hide yes)
			(effects
				(font
					(size 1 1)
					(thickness 0.15)
				)
				(justify mirror)
			)
		)
		(property "Dielectric" "X5R"
			(at 313.7 -27.3 0)
			(layer "B.Fab")
			(hide yes)
			(effects
				(font
					(size 1 1)
					(thickness 0.15)
				)
				(justify mirror)
			)
		)
		(property "License" "Apache-2.0"
			(at 313.7 -27.3 0)
			(layer "B.Fab")
			(hide yes)
			(effects
				(font
					(size 1 1)
					(thickness 0.15)
				)
				(justify mirror)
			)
		)
		(property "MPN" "GRM155R61H104KE14D"
			(at 313.7 -27.3 0)
			(layer "B.Fab")
			(hide yes)
			(effects
				(font
					(size 1 1)
					(thickness 0.15)
				)
				(justify mirror)
			)
		)
		(property "Manufacturer" "Murata"
			(at 313.7 -27.3 0)
			(layer "B.Fab")
			(hide yes)
			(effects
				(font
					(size 1 1)
					(thickness 0.15)
				)
				(justify mirror)
			)
		)
		(property "Val" "100n"
			(at 313.7 -27.3 0)
			(layer "B.Fab")
			(hide yes)
			(effects
				(font
					(size 1 1)
					(thickness 0.15)
				)
				(justify mirror)
			)
		)
		(property "Voltage" "50V"
			(at 313.7 -27.3 0)
			(layer "B.Fab")
			(hide yes)
			(effects
				(font
					(size 1 1)
					(thickness 0.15)
				)
				(justify mirror)
			)
		)
		(sheetname "DRAM + SRAM")
		(sheetfile "ram.kicad_sch")
		(attr smd)
		(fp_rect
			(start -0.925 0.47)
			(end 0.925 -0.47)
			(stroke
				(width 0.05)
				(type default)
			)
			(fill no)
			(layer "B.CrtYd")
		)
		(fp_line
			(start 0.504 -0.248)
			(end -0.494 -0.248)
			(stroke
				(width 0.15)
				(type solid)
			)
			(layer "B.Fab")
		)
		(fp_line
			(start -0.494 -0.248)
			(end -0.494 0.25)
			(stroke
				(width 0.15)
				(type solid)
			)
			(layer "B.Fab")
		)
		(fp_line
			(start 0.504 0.25)
			(end 0.504 -0.248)
			(stroke
				(width 0.15)
				(type solid)
			)
			(layer "B.Fab")
		)
		(fp_line
			(start -0.494 0.25)
			(end 0.504 0.25)
			(stroke
				(width 0.15)
				(type solid)
			)
			(layer "B.Fab")
		)
		(pad "1" smd roundrect
			(at -0.48 0 90)
			(size 0.59 0.64)
			(layers "B.Cu" "B.Mask" "B.Paste")
			(roundrect_rratio 0.25)
			(net 1 "GND")
			(pintype "passive")
		)
		(pad "2" smd roundrect
			(at 0.48 0 90)
			(size 0.59 0.64)
			(layers "B.Cu" "B.Mask" "B.Paste")
			(roundrect_rratio 0.25)
			(net 25 "+1V35")
			(pintype "passive")
		)
	)
)
